(kicad_pcb
	(version 20221018)
	(generator pcbnew)
	(general
    (thickness 1.6)
  )
	(paper "A4")
	(title_block
    (title "NUC Computer Cluster Power Breakout HW")
    (date "2023-10-18")
    (rev "1.4.3")
    (company "Antmicro Ltd.")
		(comment 9 "footprints 41-46 of 234")
	)
	(layers
    (0 "F.Cu" mixed)
    (1 "In1.Cu" power)
    (2 "In2.Cu" mixed)
    (31 "B.Cu" power)
    (32 "B.Adhes" user "B.Adhesive")
    (33 "F.Adhes" user "F.Adhesive")
    (34 "B.Paste" user)
    (35 "F.Paste" user)
    (36 "B.SilkS" user "B.Silkscreen")
    (37 "F.SilkS" user "F.Silkscreen")
    (38 "B.Mask" user)
    (39 "F.Mask" user)
    (40 "Dwgs.User" user "User.Drawings")
    (41 "Cmts.User" user "User.Comments")
    (42 "Eco1.User" user "User.Eco1")
    (43 "Eco2.User" user "User.Eco2")
    (44 "Edge.Cuts" user)
    (45 "Margin" user)
    (46 "B.CrtYd" user "B.Courtyard")
    (47 "F.CrtYd" user "F.Courtyard")
    (48 "B.Fab" user)
    (49 "F.Fab" user)
  )
	(footprint "antmicro-footprints:MOLEX_39281103" (layer "F.Cu")
    (at 94.25 78.9 90)
    (property "Author" "Antmicro")
    (property "License" "Apache-2.0")
    (property "MPN" "39-28-1103")
    (property "Manufacturer" "Molex")
    (property "Sheetfile" "daughterboard-supply.kicad_sch")
    (property "Sheetname" "daughterboard-supply")
    (property "ki_description" "Pin Header, THT, Vertical, UL94V-2, Power, Wire-to-Board, 4.2 mm, 2 Rows, 10 Contacts, Mini-fit Jr, 5566 series")
    (property "ki_keywords" "VERTICAL, THT, HEADER, CONNECTOR, MALE, WIRE-BOARD")
    (attr through_hole)
    (fp_text reference "J9" (at -4.3 -2.4 180) (layer "F.SilkS")
        (effects (font (size 0.7 0.7) (thickness 0.15)) (justify left bottom))
    )
    (fp_text value "Molex_Mini-Fit-Jr_2x5_39-28-1103" (at 4.49 11.365 90) (layer "F.Fab")
        (effects (font (size 0.7 0.7) (thickness 0.15)) (justify left bottom))
    )
    (fp_text user "License: Apache-2.0" (at -4.1 13.365 90) (layer "F.Fab") hide
        (effects (font (size 0.7 0.7) (thickness 0.15)) (justify left bottom))
    )
    (fp_text user "PTH D1.40 +/- 0.05" (at -4.1 14.565 90) (layer "F.Fab") hide
        (effects (font (size 0.7 0.7) (thickness 0.15)) (justify left bottom))
    )
    (fp_text user "Author: Antmicro" (at -4.1 16.965 90) (layer "F.Fab") hide
        (effects (font (size 0.7 0.7) (thickness 0.15)) (justify left bottom))
    )
    (fp_text user "${REFERENCE}" (at -4.1 15.765 90) (layer "F.Fab") hide
        (effects (font (size 0.7 0.7) (thickness 0.15)) (justify left bottom))
    )
    (fp_line (start -3.1 8.75) (end -3.1 -0.98)
      (stroke (width 0.15) (type solid)) (layer "F.SilkS"))
    (fp_line (start -1.83 -2.25) (end -3.1 -0.98)
      (stroke (width 0.15) (type solid)) (layer "F.SilkS"))
    (fp_line (start -1.83 -2.25) (end 19.9 -2.25)
      (stroke (width 0.15) (type solid)) (layer "F.SilkS"))
    (fp_line (start -0.4 -3.327) (end 0 -2.627)
      (stroke (width 0.15) (type solid)) (layer "F.SilkS"))
    (fp_line (start 0 -2.627) (end 0.4 -3.327)
      (stroke (width 0.15) (type solid)) (layer "F.SilkS"))
    (fp_line (start 0.4 -3.327) (end -0.4 -3.327)
      (stroke (width 0.15) (type solid)) (layer "F.SilkS"))
    (fp_line (start 19.9 -2.25) (end 19.9 8.75)
      (stroke (width 0.15) (type solid)) (layer "F.SilkS"))
    (fp_line (start 19.9 8.75) (end -3.1 8.75)
      (stroke (width 0.15) (type solid)) (layer "F.SilkS"))
    (fp_circle (center 0 -3.6) (end 0.05 -3.6)
      (stroke (width 0.15) (type solid)) (fill solid) (layer "F.SilkS"))
    (fp_circle (center 0 5.5) (end 0.513 5.5)
      (stroke (width 1.0262) (type solid)) (fill none) (layer "B.Mask"))
    (fp_circle (center 4.2 0) (end 4.713 0)
      (stroke (width 1.0262) (type solid)) (fill none) (layer "B.Mask"))
    (fp_circle (center 4.2 5.5) (end 4.713 5.5)
      (stroke (width 1.0262) (type solid)) (fill none) (layer "B.Mask"))
    (fp_circle (center 8.4 0) (end 8.913 0)
      (stroke (width 1.0262) (type solid)) (fill none) (layer "B.Mask"))
    (fp_circle (center 8.4 5.5) (end 8.913 5.5)
      (stroke (width 1.0262) (type solid)) (fill none) (layer "B.Mask"))
    (fp_circle (center 12.6 0) (end 13.113 0)
      (stroke (width 1.0262) (type solid)) (fill none) (layer "B.Mask"))
    (fp_circle (center 12.6 5.5) (end 13.113 5.5)
      (stroke (width 1.0262) (type solid)) (fill none) (layer "B.Mask"))
    (fp_circle (center 16.8 0) (end 17.313 0)
      (stroke (width 1.0262) (type solid)) (fill none) (layer "B.Mask"))
    (fp_circle (center 16.8 5.5) (end 17.313 5.5)
      (stroke (width 1.0262) (type solid)) (fill none) (layer "B.Mask"))
    (fp_poly
      (pts
        (xy -1.026 -1.026)
        (xy 1.026 -1.026)
        (xy 1.026 1.026)
        (xy -1.026 1.026)
      )

      (stroke (width 0.01) (type solid)) (fill solid) (layer "B.Mask"))
    (fp_circle (center 0 5.5) (end 0.513 5.5)
      (stroke (width 1.0262) (type solid)) (fill none) (layer "F.Mask"))
    (fp_circle (center 4.2 0) (end 4.713 0)
      (stroke (width 1.0262) (type solid)) (fill none) (layer "F.Mask"))
    (fp_circle (center 4.2 5.5) (end 4.713 5.5)
      (stroke (width 1.0262) (type solid)) (fill none) (layer "F.Mask"))
    (fp_circle (center 8.4 0) (end 8.913 0)
      (stroke (width 1.0262) (type solid)) (fill none) (layer "F.Mask"))
    (fp_circle (center 8.4 5.5) (end 8.913 5.5)
      (stroke (width 1.0262) (type solid)) (fill none) (layer "F.Mask"))
    (fp_circle (center 12.6 0) (end 13.113 0)
      (stroke (width 1.0262) (type solid)) (fill none) (layer "F.Mask"))
    (fp_circle (center 12.6 5.5) (end 13.113 5.5)
      (stroke (width 1.0262) (type solid)) (fill none) (layer "F.Mask"))
    (fp_circle (center 16.8 0) (end 17.313 0)
      (stroke (width 1.0262) (type solid)) (fill none) (layer "F.Mask"))
    (fp_circle (center 16.8 5.5) (end 17.313 5.5)
      (stroke (width 1.0262) (type solid)) (fill none) (layer "F.Mask"))
    (fp_poly
      (pts
        (xy -1.026 -1.026)
        (xy 1.026 -1.026)
        (xy 1.026 1.026)
        (xy -1.026 1.026)
      )

      (stroke (width 0.01) (type solid)) (fill solid) (layer "F.Mask"))
    (fp_rect (start -4.1 -3.3) (end 20.9 9.7)
      (stroke (width 0.05) (type solid)) (fill none) (layer "F.CrtYd"))
    (fp_line (start -3.1 8.75) (end -3.1 -0.98)
      (stroke (width 0.15) (type solid)) (layer "F.Fab"))
    (fp_line (start -1.83 -2.25) (end -3.1 -0.98)
      (stroke (width 0.15) (type solid)) (layer "F.Fab"))
    (fp_line (start -1.83 -2.25) (end 19.9 -2.25)
      (stroke (width 0.15) (type solid)) (layer "F.Fab"))
    (fp_line (start -0.4 -3.327) (end 0 -2.627)
      (stroke (width 0.15) (type solid)) (layer "F.Fab"))
    (fp_line (start 0 -2.627) (end 0.4 -3.327)
      (stroke (width 0.15) (type solid)) (layer "F.Fab"))
    (fp_line (start 0.4 -3.327) (end -0.4 -3.327)
      (stroke (width 0.15) (type solid)) (layer "F.Fab"))
    (fp_line (start 19.9 -2.25) (end 19.9 8.75)
      (stroke (width 0.15) (type solid)) (layer "F.Fab"))
    (fp_line (start 19.9 8.75) (end -3.1 8.75)
      (stroke (width 0.15) (type solid)) (layer "F.Fab"))
    (pad "1" thru_hole rect (at 0 0 90) (size 1.9 1.9) (drill 1.4) (layers "*.Cu")
      (net 11 "VCC12V0") (pinfunction "1") (pintype "bidirectional"))
    (pad "2" thru_hole circle (at 4.2 0 90) (size 1.9 1.9) (drill 1.4) (layers "*.Cu")
      (net 11 "VCC12V0") (pinfunction "2") (pintype "bidirectional"))
    (pad "3" thru_hole circle (at 8.4 0 90) (size 1.9 1.9) (drill 1.4) (layers "*.Cu")
      (net 2 "VCC5V0") (pinfunction "3") (pintype "bidirectional"))
    (pad "4" thru_hole circle (at 12.6 0 90) (size 1.9 1.9) (drill 1.4) (layers "*.Cu")
      (net 4 "GND") (pinfunction "4") (pintype "bidirectional"))
    (pad "5" thru_hole circle (at 16.8 0 90) (size 1.9 1.9) (drill 1.4) (layers "*.Cu")
      (net 1 "VCC3V3") (pinfunction "5") (pintype "bidirectional"))
    (pad "6" thru_hole circle (at 0 5.5 90) (size 1.9 1.9) (drill 1.4) (layers "*.Cu")
      (net 4 "GND") (pinfunction "6") (pintype "bidirectional"))
    (pad "7" thru_hole circle (at 4.2 5.5 90) (size 1.9 1.9) (drill 1.4) (layers "*.Cu")
      (net 4 "GND") (pinfunction "7") (pintype "bidirectional"))
    (pad "8" thru_hole circle (at 8.4 5.5 90) (size 1.9 1.9) (drill 1.4) (layers "*.Cu")
      (net 137 "Net-(J9-Pad8)") (pinfunction "8") (pintype "bidirectional"))
    (pad "9" thru_hole circle (at 12.6 5.5 90) (size 1.9 1.9) (drill 1.4) (layers "*.Cu")
      (net 4 "GND") (pinfunction "9") (pintype "bidirectional"))
    (pad "10" thru_hole circle (at 16.8 5.5 90) (size 1.9 1.9) (drill 1.4) (layers "*.Cu")
      (net 1 "VCC3V3") (pinfunction "10") (pintype "bidirectional"))
  )
	(footprint "antmicro-footprints:R_0402_1005Metric" (layer "F.Cu")
    (at 102.35 91.465 -90)
    (descr "Resistor SMD 0402")
    (tags "resistor SMD 0402")
    (property "Author" "Antmicro")
    (property "License" "Apache-2.0")
    (property "MPN" "CR0402-FX-6801GLF")
    (property "Manufacturer" "Bourns")
    (property "Sheetfile" "daughterboard-supply.kicad_sch")
    (property "Sheetname" "daughterboard-supply")
    (property "Tolerance" "1%")
    (property "Val" "6k8")
    (property "ki_description" "SMD Chip Resistor, 6.8 kohm, ± 1%, 63 mW, 0402 [1005 Metric], Thick Film, General Purpose")
    (property "ki_keywords" "0402, SMT, RESISTOR, PASSIVE")
    (attr smd)
    (fp_text reference "R34" (at 1.085 -1.5 -90) (layer "F.SilkS")
        (effects (font (size 0.7 0.7) (thickness 0.15)) (justify left bottom))
    )
    (fp_text value "R_6k8_0402" (at -1.011843 1.772047 -90) (layer "F.Fab")
        (effects (font (size 0.7 0.7) (thickness 0.15)) (justify left bottom))
    )
    (fp_text user "License: Apache-2.0" (at -0.95 5.169 -90) (layer "F.Fab") hide
        (effects (font (size 0.7 0.7) (thickness 0.15)) (justify left bottom))
    )
    (fp_text user "Author: Antmicro" (at -0.95 4.169 -90) (layer "F.Fab") hide
        (effects (font (size 0.7 0.7) (thickness 0.15)) (justify left bottom))
    )
    (fp_text user "${REFERENCE}" (at -0.95 3.168 -90) (layer "F.Fab") hide
        (effects (font (size 0.7 0.7) (thickness 0.15)) (justify left bottom))
    )
    (fp_rect (start -0.925 -0.47) (end 0.925 0.47)
      (stroke (width 0.05) (type default)) (fill none) (layer "F.CrtYd"))
    (fp_rect (start -0.5 -0.25) (end 0.5 0.25)
      (stroke (width 0.15) (type solid)) (fill none) (layer "F.Fab"))
    (pad "1" smd roundrect (at -0.48 0 270) (size 0.59 0.64) (layers "F.Cu" "F.Paste" "F.Mask") (roundrect_rratio 0.25)
      (net 2 "VCC5V0") (pintype "passive"))
    (pad "2" smd roundrect (at 0.48 0 270) (size 0.59 0.64) (layers "F.Cu" "F.Paste" "F.Mask") (roundrect_rratio 0.25)
      (net 111 "Net-(U15-FB)") (pintype "passive"))
  )
	(footprint "antmicro-footprints:R_0402_1005Metric" (layer "F.Cu")
    (at 148.7 91.8 -90)
    (descr "Resistor SMD 0402")
    (tags "resistor SMD 0402")
    (property "Author" "Antmicro")
    (property "License" "Apache-2.0")
    (property "MPN" "CR0402-FX-4701GLF")
    (property "Manufacturer" "Bourns")
    (property "Sheetfile" "power-switch.kicad_sch")
    (property "Sheetname" "Power switch 3")
    (property "Tolerance" "1%")
    (property "Val" "4k7")
    (property "ki_description" "SMD Chip Resistor, 4.7 kohm, ± 1%, 62.5 mW, 0402 [1005 Metric], Thick Film, General Purpose")
    (property "ki_keywords" "0402, SMT, RESISTOR, PASSIVE")
    (zone_connect 1)
    (attr smd)
    (fp_text reference "R29" (at 1.5 -0.1) (layer "F.SilkS")
        (effects (font (size 0.7 0.7) (thickness 0.15)))
    )
    (fp_text value "R_4k7_0402" (at 0 1.17 90) (layer "F.Fab") hide
        (effects (font (size 1 1) (thickness 0.15)))
    )
    (fp_text user "License: Apache-2.0" (at -0.95 5.169 90) (layer "F.Fab") hide
        (effects (font (size 0.7 0.7) (thickness 0.15)) (justify right bottom))
    )
    (fp_text user "${REFERENCE}" (at 0 0 90) (layer "F.Fab")
        (effects (font (size 0.7 0.7) (thickness 0.15)))
    )
    (fp_text user "Author: Antmicro" (at -0.95 4.169 90) (layer "F.Fab") hide
        (effects (font (size 0.7 0.7) (thickness 0.15)) (justify right bottom))
    )
    (fp_rect (start -0.925 -0.47) (end 0.925 0.47)
      (stroke (width 0.05) (type default)) (fill none) (layer "F.CrtYd"))
    (fp_rect (start -0.5 -0.25) (end 0.5 0.25)
      (stroke (width 0.15) (type solid)) (fill none) (layer "F.Fab"))
    (pad "1" smd roundrect (at -0.48 0 270) (size 0.59 0.64) (layers "F.Cu" "F.Paste" "F.Mask") (roundrect_rratio 0.25)
      (net 11 "VCC12V0") (pintype "passive"))
    (pad "2" smd roundrect (at 0.48 0 270) (size 0.59 0.64) (layers "F.Cu" "F.Paste" "F.Mask") (roundrect_rratio 0.25)
      (net 86 "Net-(D18-A)") (pintype "passive"))
  )
	(footprint "antmicro-footprints:SOIC-8_3.9x4.9x1.75mm_P1.27mm" (layer "F.Cu")
    (at 165.25 82.15 180)
    (property "Author" "Antmicro")
    (property "License" "Apache-2.0")
    (property "MPN" "TMCS1100A2QDRQ1")
    (property "Manufacturer" "Texas Instruments")
    (property "Sheetfile" "pow-cycl-curr-meas.kicad_sch")
    (property "Sheetname" "Power Cycling & Current Measurement")
    (property "ki_description" "Hall current Sensor/transducer")
    (property "ki_keywords" "SMT, SENSOR, IC, POWER")
    (attr smd)
    (fp_text reference "U12" (at 1.15 2.85) (layer "F.SilkS")
        (effects (font (size 0.7 0.7) (thickness 0.15)) (justify right bottom))
    )
    (fp_text value "TMCS1100A2-Q1" (at 0 3.65) (layer "F.Fab")
        (effects (font (size 0.7 0.7) (thickness 0.15)) (justify right bottom))
    )
    (fp_text user "${REFERENCE}" (at -3.476 7.099) (layer "F.Fab") hide
        (effects (font (size 0.7 0.7) (thickness 0.15)) (justify right bottom))
    )
    (fp_text user "License: Apache-2.0" (at -3.476 5.099) (layer "F.Fab") hide
        (effects (font (size 0.7 0.7) (thickness 0.15)) (justify right bottom))
    )
    (fp_text user "Author: Antmicro" (at -3.476 6.099) (layer "F.Fab") hide
        (effects (font (size 0.7 0.7) (thickness 0.15)) (justify right bottom))
    )
    (fp_line (start -1.95 -2.452) (end 1.95 -2.45)
      (stroke (width 0.15) (type solid)) (layer "F.SilkS"))
    (fp_line (start -1.95 2.45) (end 1.95 2.45)
      (stroke (width 0.15) (type solid)) (layer "F.SilkS"))
    (fp_circle (center -2.4 -2.45) (end -2.35 -2.4)
      (stroke (width 0.15) (type solid)) (fill solid) (layer "F.SilkS"))
    (fp_rect (start -3.625 -2.7) (end 3.625 2.7)
      (stroke (width 0.05) (type solid)) (fill none) (layer "F.CrtYd"))
    (fp_line (start -1.95 -1.18) (end -0.683 -2.452)
      (stroke (width 0.15) (type solid)) (layer "F.Fab"))
    (fp_line (start -1.95 2.45) (end -1.95 -1.18)
      (stroke (width 0.15) (type solid)) (layer "F.Fab"))
    (fp_line (start -0.683 -2.452) (end 1.949 -2.452)
      (stroke (width 0.15) (type solid)) (layer "F.Fab"))
    (fp_line (start 1.949 -2.452) (end 1.949 2.45)
      (stroke (width 0.15) (type solid)) (layer "F.Fab"))
    (fp_line (start 1.949 2.45) (end -1.95 2.45)
      (stroke (width 0.15) (type solid)) (layer "F.Fab"))
    (pad "1" smd roundrect (at -2.714 -1.905 270) (size 0.65 1.525) (layers "F.Cu" "F.Paste" "F.Mask") (roundrect_rratio 0.25)
      (net 27 "C_MEAS_4") (pinfunction "IN+") (pintype "input"))
    (pad "2" smd roundrect (at -2.714 -0.635 270) (size 0.65 1.525) (layers "F.Cu" "F.Paste" "F.Mask") (roundrect_rratio 0.25)
      (net 27 "C_MEAS_4") (pinfunction "IN+") (pintype "input"))
    (pad "3" smd roundrect (at -2.714 0.632 270) (size 0.65 1.525) (layers "F.Cu" "F.Paste" "F.Mask") (roundrect_rratio 0.25)
      (net 45 "LOAD_4") (pinfunction "IN-") (pintype "input"))
    (pad "4" smd roundrect (at -2.714 1.902 270) (size 0.65 1.525) (layers "F.Cu" "F.Paste" "F.Mask") (roundrect_rratio 0.25)
      (net 45 "LOAD_4") (pinfunction "IN-") (pintype "input"))
    (pad "5" smd roundrect (at 2.712 1.902 270) (size 0.65 1.525) (layers "F.Cu" "F.Paste" "F.Mask") (roundrect_rratio 0.25)
      (net 4 "GND") (pinfunction "GND") (pintype "power_in"))
    (pad "6" smd roundrect (at 2.712 0.632 270) (size 0.65 1.525) (layers "F.Cu" "F.Paste" "F.Mask") (roundrect_rratio 0.25)
      (net 4 "GND") (pinfunction "VREF") (pintype "input"))
    (pad "7" smd roundrect (at 2.712 -0.635 270) (size 0.65 1.525) (layers "F.Cu" "F.Paste" "F.Mask") (roundrect_rratio 0.25)
      (net 49 "/Power Cycling & Current Measurement/C_ADC4") (pinfunction "VOUT") (pintype "output"))
    (pad "8" smd roundrect (at 2.712 -1.905 270) (size 0.65 1.525) (layers "F.Cu" "F.Paste" "F.Mask") (roundrect_rratio 0.25)
      (net 1 "VCC3V3") (pinfunction "VCC") (pintype "power_in"))
  )
	(footprint "antmicro-footprints:R_0402_1005Metric" (layer "F.Cu")
    (at 101.25 92.45 -90)
    (descr "Resistor SMD 0402")
    (tags "resistor SMD 0402")
    (property "Author" "Antmicro")
    (property "License" "Apache-2.0")
    (property "MPN" "CR0402-FX-1301GLF")
    (property "Manufacturer" "Bourns")
    (property "Sheetfile" "daughterboard-supply.kicad_sch")
    (property "Sheetname" "daughterboard-supply")
    (property "Tolerance" "1%")
    (property "Val" "1k3")
    (property "ki_description" "SMD Chip Resistor, 1.3 kohm, ± 1%, 62.5 mW, 0402 [1005 Metric], Thick Film, General Purpose")
    (property "ki_keywords" "0402, SMT, RESISTOR, PASSIVE")
    (attr smd)
    (fp_text reference "R35" (at -0.85 -0.4 -90) (layer "F.SilkS")
        (effects (font (size 0.7 0.7) (thickness 0.15)) (justify left bottom))
    )
    (fp_text value "R_1k3_0402" (at -1.011843 1.772047 -90) (layer "F.Fab")
        (effects (font (size 0.7 0.7) (thickness 0.15)) (justify left bottom))
    )
    (fp_text user "License: Apache-2.0" (at -0.95 5.169 -90) (layer "F.Fab") hide
        (effects (font (size 0.7 0.7) (thickness 0.15)) (justify left bottom))
    )
    (fp_text user "Author: Antmicro" (at -0.95 4.169 -90) (layer "F.Fab") hide
        (effects (font (size 0.7 0.7) (thickness 0.15)) (justify left bottom))
    )
    (fp_text user "${REFERENCE}" (at -0.95 3.168 -90) (layer "F.Fab") hide
        (effects (font (size 0.7 0.7) (thickness 0.15)) (justify left bottom))
    )
    (fp_rect (start -0.925 -0.47) (end 0.925 0.47)
      (stroke (width 0.05) (type default)) (fill none) (layer "F.CrtYd"))
    (fp_rect (start -0.5 -0.25) (end 0.5 0.25)
      (stroke (width 0.15) (type solid)) (fill none) (layer "F.Fab"))
    (pad "1" smd roundrect (at -0.48 0 270) (size 0.59 0.64) (layers "F.Cu" "F.Paste" "F.Mask") (roundrect_rratio 0.25)
      (net 111 "Net-(U15-FB)") (pintype "passive"))
    (pad "2" smd roundrect (at 0.48 0 270) (size 0.59 0.64) (layers "F.Cu" "F.Paste" "F.Mask") (roundrect_rratio 0.25)
      (net 4 "GND") (pintype "passive"))
  )
	(footprint "antmicro-footprints:TP_SMD_1mm" (layer "F.Cu")
    (at 175.6 99)
    (property "Author" "Antmicro")
    (property "License" "Apache-2.0")
    (property "MPN" "")
    (property "Manufacturer" "")
    (property "Sheetfile" "ftdi-module.kicad_sch")
    (property "Sheetname" "FTDI")
    (property "exclude_from_bom" "")
    (property "ki_description" "Test point 1mm SMD")
    (property "ki_keywords" "TESTPOINT")
    (attr exclude_from_pos_files exclude_from_bom)
    (fp_text reference "SCL1" (at -1.825 0 180) (layer "F.SilkS")
        (effects (font (size 0.7 0.7) (thickness 0.15)))
    )
    (fp_text value "TP_1mm_SMD" (at 0 -0.5) (layer "F.Fab") hide
        (effects (font (size 1 1) (thickness 0.15)))
    )
    (fp_text user "${REFERENCE}" (at -0.5 2.8) (layer "F.Fab") hide
        (effects (font (size 0.7 0.7) (thickness 0.15)) (justify left bottom))
    )
    (fp_text user "License: Apache-2.0" (at -0.5 5.2) (layer "F.Fab") hide
        (effects (font (size 0.7 0.7) (thickness 0.15)) (justify left bottom))
    )
    (fp_text user "Author: Antmicro" (at -0.5 4) (layer "F.Fab") hide
        (effects (font (size 0.7 0.7) (thickness 0.15)) (justify left bottom))
    )
    (fp_circle (center 0 0) (end 0.6 0)
      (stroke (width 0.05) (type default)) (fill none) (layer "F.CrtYd"))
    (pad "1" smd circle (at 0 0) (size 1 1) (layers "F.Cu" "F.Mask")
      (net 17 "SCL") (pinfunction "1") (pintype "passive"))
  )
)
